# S9S_MB_2U (Grand Teton) — schematic netlist excerpt (pin names and nets, part order shuffled) for the footprints in the layout excerpt that follows; sources: Cadence DE-HDL packaged netlist, KiCad conversion of 03242023_DA0F0TMBIJ0_F0T_Motherboard_J_brd_V01_OCP.brd

C2257  Q_CAP  0.1UF 25V 10% X7R  pkg 0402  page 212 : A = VFG3P3_CLK_GEN ; B = GND
R2478  Q_RES  33.2 1% CHIP  pkg 0402LF  page 235 : A = SMB_PEHPCPU0_LVC3_SDA_R0 ; B = SMB_PEHPCPU0_LVC3_SDA
C482  Q_CAP  47UF 4V 20% X6S  pkg C0805  page 79 : A = PVCCFA_EHV_FIVRA_CPU1 ; B = GND

(kicad_pcb
	(version 20260206)
	(generator "pcbnew")
	(generator_version "10.0")
	(general
		(thickness 1.6)
		(legacy_teardrops no)
	)
	(paper "A4")
	(title_block
		(title "03242023_DA0F0TMBIJ0_F0T_Motherboard_J_brd_V01_OCP.brd")
		(comment 1 "Grand Teton / footprints 5559-5561 of 6105")
	)
	(layers
		(0 "F.Cu" signal "TOP")
		(4 "In1.Cu" signal "GND")
		(6 "In2.Cu" signal "IN1")
		(8 "In3.Cu" signal "GND1")
		(10 "In4.Cu" signal "IN2")
		(12 "In5.Cu" signal "GND2")
		(14 "In6.Cu" signal "IN3")
		(16 "In7.Cu" signal "GND3")
		(18 "In8.Cu" signal "VCC")
		(20 "In9.Cu" signal "VCC1")
		(22 "In10.Cu" signal "GND4")
		(24 "In11.Cu" signal "IN4")
		(26 "In12.Cu" signal "GND5")
		(28 "In13.Cu" signal "IN5")
		(30 "In14.Cu" signal "GND6")
		(32 "In15.Cu" signal "IN6")
		(34 "In16.Cu" signal "GND7")
		(2 "B.Cu" signal "BOTTOM")
		(9 "F.Adhes" user "F.Adhesive")
		(11 "B.Adhes" user "B.Adhesive")
		(13 "F.Paste" user "Package Geometry/Pastemask Top")
		(15 "B.Paste" user "Package Geometry/Pastemask Bottom")
		(5 "F.SilkS" user "Ref Des/Silkscreen Top")
		(7 "B.SilkS" user "Ref Des/Silkscreen Bottom")
		(1 "F.Mask" user "Board Geometry/Soldermask Top")
		(3 "B.Mask" user "Board Geometry/Soldermask Bottom")
		(17 "Dwgs.User" user "User.Drawings")
		(19 "Cmts.User" user "User.Comments")
		(21 "Eco1.User" user "User.Eco1")
		(23 "Eco2.User" user "User.Eco2")
		(25 "Edge.Cuts" user "Board Geometry/Outline")
		(27 "Margin" user)
		(31 "F.CrtYd" user "Package Geometry/Place Bound Top")
		(29 "B.CrtYd" user "Package Geometry/Place Bound Bottom")
		(35 "F.Fab" user "Ref Des/Assembly Top")
		(33 "B.Fab" user "Ref Des/Assembly Bottom")
	)
	(footprint ""
		(layer "B.Cu")
		(at 236.89056 -249.037348)
		(property "Reference" "C2257"
			(at 0 0 0)
			(layer "B.SilkS")
			(hide yes)
			(effects
				(font
					(size 1.27 1.27)
				)
				(justify mirror)
			)
		)
		(property "Value" ""
			(at 0 0 0)
			(layer "B.Fab")
			(effects
				(font
					(size 1.27 1.27)
				)
				(justify mirror)
			)
		)
		(duplicate_pad_numbers_are_jumpers no)
		(fp_line
			(start -0.7874 -0.4064)
			(end -0.7874 0.4064)
			(stroke
				(width 0.1524)
				(type default)
			)
			(layer "B.SilkS")
		)
		(fp_line
			(start -0.7874 0.4064)
			(end 0.7874 0.4064)
			(stroke
				(width 0.1524)
				(type default)
			)
			(layer "B.SilkS")
		)
		(fp_line
			(start 0.7874 -0.4064)
			(end -0.7874 -0.4064)
			(stroke
				(width 0.1524)
				(type default)
			)
			(layer "B.SilkS")
		)
		(fp_line
			(start 0.7874 0.4064)
			(end 0.7874 -0.4064)
			(stroke
				(width 0.1524)
				(type default)
			)
			(layer "B.SilkS")
		)
		(fp_line
			(start -0.67945 -0.3048)
			(end -0.67945 0.3048)
			(stroke
				(width 0.1)
				(type default)
			)
			(layer "B.Fab")
		)
		(fp_line
			(start -0.67945 0.3048)
			(end -0.120396 0.3048)
			(stroke
				(width 0.1)
				(type default)
			)
			(layer "B.Fab")
		)
		(fp_line
			(start -0.12065 -0.3048)
			(end -0.67945 -0.3048)
			(stroke
				(width 0.1)
				(type default)
			)
			(layer "B.Fab")
		)
		(fp_line
			(start -0.12065 -0.2794)
			(end -0.12065 -0.3048)
			(stroke
				(width 0.1)
				(type default)
			)
			(layer "B.Fab")
		)
		(fp_line
			(start -0.120396 0.2794)
			(end 0.12065 0.2794)
			(stroke
				(width 0.1)
				(type default)
			)
			(layer "B.Fab")
		)
		(fp_line
			(start -0.120396 0.3048)
			(end -0.120396 0.2794)
			(stroke
				(width 0.1)
				(type default)
			)
			(layer "B.Fab")
		)
		(fp_line
			(start 0.12065 -0.305054)
			(end 0.12065 -0.2794)
			(stroke
				(width 0.1)
				(type default)
			)
			(layer "B.Fab")
		)
		(fp_line
			(start 0.12065 -0.2794)
			(end -0.12065 -0.2794)
			(stroke
				(width 0.1)
				(type default)
			)
			(layer "B.Fab")
		)
		(fp_line
			(start 0.12065 0.2794)
			(end 0.12065 0.3048)
			(stroke
				(width 0.1)
				(type default)
			)
			(layer "B.Fab")
		)
		(fp_line
			(start 0.12065 0.3048)
			(end 0.67945 0.3048)
			(stroke
				(width 0.1)
				(type default)
			)
			(layer "B.Fab")
		)
		(fp_line
			(start 0.67945 -0.305054)
			(end 0.12065 -0.305054)
			(stroke
				(width 0.1)
				(type default)
			)
			(layer "B.Fab")
		)
		(fp_line
			(start 0.67945 0.3048)
			(end 0.67945 -0.305054)
			(stroke
				(width 0.1)
				(type default)
			)
			(layer "B.Fab")
		)
		(pad "1" smd circle
			(at 0.40005 0 180)
			(size 0 0)
			(layers "B.Cu" "B.Mask" "B.Paste")
			(net "VFG3P3_CLK_GEN")
		)
		(pad "2" smd circle
			(at -0.40005 0 180)
			(size 0 0)
			(layers "B.Cu" "B.Mask" "B.Paste")
			(net "GND")
		)
	)
	(footprint ""
		(layer "B.Cu")
		(at 164.725858 -256.488946 -90)
		(property "Reference" "C482"
			(at 0 0 90)
			(layer "B.SilkS")
			(hide yes)
			(effects
				(font
					(size 1.27 1.27)
				)
				(justify mirror)
			)
		)
		(property "Value" ""
			(at 0 0 90)
			(layer "B.Fab")
			(effects
				(font
					(size 1.27 1.27)
				)
				(justify mirror)
			)
		)
		(duplicate_pad_numbers_are_jumpers no)
		(fp_line
			(start -1.524 0.762)
			(end 1.524 0.762)
			(stroke
				(width 0.1524)
				(type default)
			)
			(layer "B.SilkS")
		)
		(fp_line
			(start 1.524 0.762)
			(end 1.524 -0.762)
			(stroke
				(width 0.1524)
				(type default)
			)
			(layer "B.SilkS")
		)
		(fp_line
			(start -1.524 -0.762)
			(end -1.524 0.762)
			(stroke
				(width 0.1524)
				(type default)
			)
			(layer "B.SilkS")
		)
		(fp_line
			(start 1.524 -0.762)
			(end -1.524 -0.762)
			(stroke
				(width 0.1524)
				(type default)
			)
			(layer "B.SilkS")
		)
		(fp_line
			(start -1.1049 0.724916)
			(end -1.1049 -0.724916)
			(stroke
				(width 0.1)
				(type default)
			)
			(layer "B.Fab")
		)
		(fp_line
			(start 1.1049 0.724916)
			(end -1.1049 0.724916)
			(stroke
				(width 0.1)
				(type default)
			)
			(layer "B.Fab")
		)
		(fp_line
			(start -1.1049 -0.724916)
			(end 1.1049 -0.724916)
			(stroke
				(width 0.1)
				(type default)
			)
			(layer "B.Fab")
		)
		(fp_line
			(start 1.1049 -0.724916)
			(end 1.1049 0.724916)
			(stroke
				(width 0.1)
				(type default)
			)
			(layer "B.Fab")
		)
		(pad "1" smd rect
			(at 0.889 0 270)
			(size 1.016 1.27)
			(layers "B.Cu" "B.Mask" "B.Paste")
			(net "PVCCFA_EHV_FIVRA_CPU1")
		)
		(pad "2" smd rect
			(at -0.889 0 270)
			(size 1.016 1.27)
			(layers "B.Cu" "B.Mask" "B.Paste")
			(net "GND")
		)
	)
	(footprint ""
		(layer "B.Cu")
		(at 367.034572 -184.400952 90)
		(property "Reference" "R2478"
			(at 0 0 90)
			(layer "B.SilkS")
			(hide yes)
			(effects
				(font
					(size 1.27 1.27)
				)
				(justify mirror)
			)
		)
		(property "Value" ""
			(at 0 0 90)
			(layer "B.Fab")
			(effects
				(font
					(size 1.27 1.27)
				)
				(justify mirror)
			)
		)
		(duplicate_pad_numbers_are_jumpers no)
		(fp_line
			(start 0.7874 -0.4064)
			(end -0.7874 -0.4064)
			(stroke
				(width 0.1524)
				(type default)
			)
			(layer "B.SilkS")
		)
		(fp_line
			(start -0.7874 -0.4064)
			(end -0.7874 0.4064)
			(stroke
				(width 0.1524)
				(type default)
			)
			(layer "B.SilkS")
		)
		(fp_line
			(start 0.7874 0.4064)
			(end 0.7874 -0.4064)
			(stroke
				(width 0.1524)
				(type default)
			)
			(layer "B.SilkS")
		)
		(fp_line
			(start -0.7874 0.4064)
			(end 0.7874 0.4064)
			(stroke
				(width 0.1524)
				(type default)
			)
			(layer "B.SilkS")
		)
		(fp_line
			(start 0.67945 -0.305054)
			(end 0.12065 -0.305054)
			(stroke
				(width 0.1)
				(type default)
			)
			(layer "B.Fab")
		)
		(fp_line
			(start 0.12065 -0.305054)
			(end 0.12065 -0.2794)
			(stroke
				(width 0.1)
				(type default)
			)
			(layer "B.Fab")
		)
		(fp_line
			(start -0.12065 -0.3048)
			(end -0.67945 -0.3048)
			(stroke
				(width 0.1)
				(type default)
			)
			(layer "B.Fab")
		)
		(fp_line
			(start -0.67945 -0.3048)
			(end -0.67945 0.3048)
			(stroke
				(width 0.1)
				(type default)
			)
			(layer "B.Fab")
		)
		(fp_line
			(start 0.12065 -0.2794)
			(end -0.12065 -0.2794)
			(stroke
				(width 0.1)
				(type default)
			)
			(layer "B.Fab")
		)
		(fp_line
			(start -0.12065 -0.2794)
			(end -0.12065 -0.3048)
			(stroke
				(width 0.1)
				(type default)
			)
			(layer "B.Fab")
		)
		(fp_line
			(start 0.12065 0.2794)
			(end 0.12065 0.3048)
			(stroke
				(width 0.1)
				(type default)
			)
			(layer "B.Fab")
		)
		(fp_line
			(start -0.120396 0.2794)
			(end 0.12065 0.2794)
			(stroke
				(width 0.1)
				(type default)
			)
			(layer "B.Fab")
		)
		(fp_line
			(start 0.67945 0.3048)
			(end 0.67945 -0.305054)
			(stroke
				(width 0.1)
				(type default)
			)
			(layer "B.Fab")
		)
		(fp_line
			(start 0.12065 0.3048)
			(end 0.67945 0.3048)
			(stroke
				(width 0.1)
				(type default)
			)
			(layer "B.Fab")
		)
		(fp_line
			(start -0.120396 0.3048)
			(end -0.120396 0.2794)
			(stroke
				(width 0.1)
				(type default)
			)
			(layer "B.Fab")
		)
		(fp_line
			(start -0.67945 0.3048)
			(end -0.120396 0.3048)
			(stroke
				(width 0.1)
				(type default)
			)
			(layer "B.Fab")
		)
		(pad "1" smd circle
			(at 0.40005 0 270)
			(size 0 0)
			(layers "B.Cu" "B.Mask" "B.Paste")
			(net "SMB_PEHPCPU0_LVC3_SDA_R0")
		)
		(pad "2" smd circle
			(at -0.40005 0 270)
			(size 0 0)
			(layers "B.Cu" "B.Mask" "B.Paste")
			(net "SMB_PEHPCPU0_LVC3_SDA")
		)
	)
)
